(kicad_pcb
	(version 20221018)
	(generator pcbnew)
	(general
    (thickness 1.62)
  )
	(paper "A4")
	(title_block
    (title "ECP5 - Datacenter Secure Control Module (DC-SCM)")
    (date "2024-07-01")
    (rev "1.2.1")
		(comment 9 "footprints 474-482 of 506")
	)
	(layers
    (0 "F.Cu" signal)
    (1 "In1.Cu" power)
    (2 "In2.Cu" signal)
    (3 "In3.Cu" power)
    (4 "In4.Cu" power)
    (5 "In5.Cu" signal)
    (6 "In6.Cu" power)
    (31 "B.Cu" signal)
    (32 "B.Adhes" user "B.Adhesive")
    (33 "F.Adhes" user "F.Adhesive")
    (34 "B.Paste" user)
    (35 "F.Paste" user)
    (36 "B.SilkS" user "B.Silkscreen")
    (37 "F.SilkS" user "F.Silkscreen")
    (38 "B.Mask" user)
    (39 "F.Mask" user)
    (40 "Dwgs.User" user "User.Drawings")
    (41 "Cmts.User" user "User.Comments")
    (42 "Eco1.User" user "User.Eco1")
    (43 "Eco2.User" user "User.Eco2")
    (44 "Edge.Cuts" user)
    (45 "Margin" user)
    (46 "B.CrtYd" user "B.Courtyard")
    (47 "F.CrtYd" user "F.Courtyard")
    (48 "B.Fab" user)
    (49 "F.Fab" user)
  )
	(footprint "antmicro-footprints:C_0402_1005Metric" (layer "B.Cu")
    (at 140.8 83.64 90)
    (descr "Capacitor SMD 0402")
    (tags "capacitor SMD 0402")
    (property "Author" "Antmicro")
    (property "Dielectric" "X5R")
    (property "License" "Apache-2.0")
    (property "MPN" "GRM155R61H104KE14D")
    (property "Manufacturer" "Murata")
    (property "Public" "False")
    (property "Sheetfile" "interfaces.kicad_sch")
    (property "Sheetname" "Interfaces")
    (property "Val" "100n")
    (property "Voltage" "50V")
    (property "ki_description" "SMD Multilayer Ceramic Capacitor, 0.1 µF, 50 V, 0402 [1005 Metric], ± 10%, X5R, GRM Series")
    (property "ki_keywords" "0402, SMT, CAPACITOR, PASSIVE, CERAMIC, MLCC")
    (attr smd)
    (fp_text reference "C98" (at -0.035 1.42 90) (layer "B.SilkS")
        (effects (font (size 0.7 0.7) (thickness 0.15)) (justify mirror))
    )
    (fp_text value "C_100n_0402" (at 0 -1.17 90) (layer "B.Fab")
        (effects (font (size 1 1) (thickness 0.15)) (justify mirror))
    )
    (fp_text user "${REFERENCE}" (at 0 0 90) (layer "B.Fab")
        (effects (font (size 0.25 0.25) (thickness 0.04)) (justify mirror))
    )
    (fp_text user "License: Apache-2.0" (at -0.939 -5.799 270) (layer "B.Fab") hide
        (effects (font (size 0.7 0.7) (thickness 0.15)) (justify left bottom mirror))
    )
    (fp_text user "Author: Antmicro" (at -0.939 -3.399 270) (layer "B.Fab") hide
        (effects (font (size 0.7 0.7) (thickness 0.15)) (justify left bottom mirror))
    )
    (fp_rect (start -0.925 0.47) (end 0.925 -0.47)
      (stroke (width 0.05) (type default)) (fill none) (layer "B.CrtYd"))
    (fp_line (start -0.494 -0.248) (end -0.494 0.25)
      (stroke (width 0.15) (type solid)) (layer "B.Fab"))
    (fp_line (start -0.494 0.25) (end 0.504 0.25)
      (stroke (width 0.15) (type solid)) (layer "B.Fab"))
    (fp_line (start 0.504 -0.248) (end -0.494 -0.248)
      (stroke (width 0.15) (type solid)) (layer "B.Fab"))
    (fp_line (start 0.504 0.25) (end 0.504 -0.248)
      (stroke (width 0.15) (type solid)) (layer "B.Fab"))
    (pad "1" smd roundrect (at -0.48 0 90) (size 0.59 0.64) (layers "B.Cu" "B.Paste" "B.Mask") (roundrect_rratio 0.25)
      (net 1 "GND") (pintype "passive"))
    (pad "2" smd roundrect (at 0.48 0 90) (size 0.59 0.64) (layers "B.Cu" "B.Paste" "B.Mask") (roundrect_rratio 0.25)
      (net 415 "VBUS") (pintype "passive"))
  )
	(footprint "antmicro-footprints:C_0402_1005Metric" (layer "B.Cu")
    (at 138.65 83.675 90)
    (descr "Capacitor SMD 0402")
    (tags "capacitor SMD 0402")
    (property "Author" "Antmicro")
    (property "Dielectric" "")
    (property "License" "Apache-2.0")
    (property "MPN" "GRM155R61A475MEAAD")
    (property "Manufacturer" "Murata")
    (property "Public" "False")
    (property "Sheetfile" "interfaces.kicad_sch")
    (property "Sheetname" "Interfaces")
    (property "Val" "4u7")
    (property "Voltage" "")
    (property "ki_description" "SMD Multilayer Ceramic Capacitor, 4.7 µF, 10 V, 0402 [1005 Metric], ± 20%, X5R, GRM Series")
    (property "ki_keywords" "0402, SMT, CAPACITOR, PASSIVE")
    (attr smd)
    (fp_text reference "C99" (at 2 0.07 90) (layer "B.SilkS")
        (effects (font (size 0.7 0.7) (thickness 0.15)) (justify mirror))
    )
    (fp_text value "C_4u7_0402" (at 0 -1.17 90) (layer "B.Fab")
        (effects (font (size 1 1) (thickness 0.15)) (justify mirror))
    )
    (fp_text user "License: Apache-2.0" (at -0.939 -5.799 270) (layer "B.Fab") hide
        (effects (font (size 0.7 0.7) (thickness 0.15)) (justify left bottom mirror))
    )
    (fp_text user "${REFERENCE}" (at 0 0 90) (layer "B.Fab")
        (effects (font (size 0.25 0.25) (thickness 0.04)) (justify mirror))
    )
    (fp_text user "Author: Antmicro" (at -0.939 -3.399 270) (layer "B.Fab") hide
        (effects (font (size 0.7 0.7) (thickness 0.15)) (justify left bottom mirror))
    )
    (fp_rect (start -0.925 0.47) (end 0.925 -0.47)
      (stroke (width 0.05) (type default)) (fill none) (layer "B.CrtYd"))
    (fp_line (start -0.494 -0.248) (end -0.494 0.25)
      (stroke (width 0.15) (type solid)) (layer "B.Fab"))
    (fp_line (start -0.494 0.25) (end 0.504 0.25)
      (stroke (width 0.15) (type solid)) (layer "B.Fab"))
    (fp_line (start 0.504 -0.248) (end -0.494 -0.248)
      (stroke (width 0.15) (type solid)) (layer "B.Fab"))
    (fp_line (start 0.504 0.25) (end 0.504 -0.248)
      (stroke (width 0.15) (type solid)) (layer "B.Fab"))
    (pad "1" smd roundrect (at -0.48 0 90) (size 0.59 0.64) (layers "B.Cu" "B.Paste" "B.Mask") (roundrect_rratio 0.25)
      (net 1 "GND") (pintype "passive"))
    (pad "2" smd roundrect (at 0.48 0 90) (size 0.59 0.64) (layers "B.Cu" "B.Paste" "B.Mask") (roundrect_rratio 0.25)
      (net 415 "VBUS") (pintype "passive"))
  )
	(footprint "antmicro-footprints:FB_0402_1005Metric" (layer "B.Cu")
    (at 136.4 83.675 -90)
    (descr "Ferrite Bead SMD 0402")
    (tags "ferrite bead SMD 0402")
    (property "Author" "Antmicro")
    (property "Current" "")
    (property "License" "Apache-2.0")
    (property "MPN" "BLM15AG601SN1D")
    (property "Manufacturer" "Murata")
    (property "Public" "False")
    (property "Sheetfile" "interfaces.kicad_sch")
    (property "Sheetname" "Interfaces")
    (property "Val" "600Z/0.3A")
    (property "ki_description" "Ferrite Bead, 0402 [1005 Metric], 600 ohm, 300 mA, BLM15AG_SN, 0.6 ohm, ± 25%, General use")
    (property "ki_keywords" "0402, SMT, FERRITE BEAD, PASSIVE")
    (attr smd)
    (fp_text reference "FB9" (at -2.918333 -0.06 90) (layer "B.SilkS")
        (effects (font (size 0.7 0.7) (thickness 0.15)) (justify mirror))
    )
    (fp_text value "FB_600Z_0.3A_Murata-BLM15AG_0402" (at 0 -1.17 90) (layer "B.Fab")
        (effects (font (size 1 1) (thickness 0.15)) (justify mirror))
    )
    (fp_text user "License: Apache-2.0" (at -0.95 -5.169 90) (layer "B.Fab") hide
        (effects (font (size 0.7 0.7) (thickness 0.15)) (justify left bottom mirror))
    )
    (fp_text user "${REFERENCE}" (at 0 0 90) (layer "B.Fab")
        (effects (font (size 0.25 0.25) (thickness 0.04)) (justify mirror))
    )
    (fp_text user "Author: Antmicro" (at -0.95 -4.169 90) (layer "B.Fab") hide
        (effects (font (size 0.7 0.7) (thickness 0.15)) (justify left bottom mirror))
    )
    (fp_rect (start -0.925 0.47) (end 0.925 -0.47)
      (stroke (width 0.05) (type default)) (fill none) (layer "B.CrtYd"))
    (fp_rect (start -0.5 0.25) (end 0.5 -0.25)
      (stroke (width 0.15) (type solid)) (fill none) (layer "B.Fab"))
    (pad "1" smd roundrect (at -0.48 0 270) (size 0.59 0.64) (layers "B.Cu" "B.Paste" "B.Mask") (roundrect_rratio 0.25)
      (net 2 "VCC3V3") (pintype "passive"))
    (pad "2" smd roundrect (at 0.48 0 270) (size 0.59 0.64) (layers "B.Cu" "B.Paste" "B.Mask") (roundrect_rratio 0.25)
      (net 306 "Net-(U14-V_{PLL})") (pintype "passive"))
  )
	(footprint "antmicro-footprints:R_0402_1005Metric" (layer "B.Cu")
    (at 137.1 86.325 -90)
    (descr "Resistor SMD 0402")
    (tags "resistor SMD 0402")
    (property "Author" "Antmicro")
    (property "License" "Apache-2.0")
    (property "MPN" "CR0402-FX-1202GLF")
    (property "Manufacturer" "Bourns")
    (property "Public" "False")
    (property "Sheetfile" "interfaces.kicad_sch")
    (property "Sheetname" "Interfaces")
    (property "Tolerance" "1%")
    (property "Val" "12k")
    (property "ki_description" "SMD Chip Resistor, 12 kohm, ± 1%, 62.5 mW, 0402 [1005 Metric], Thick Film, General Purpose")
    (property "ki_keywords" "0402, SMT, RESISTOR, PASSIVE")
    (attr smd)
    (fp_text reference "R149" (at 3.1 0.05 90) (layer "B.SilkS")
        (effects (font (size 0.7 0.7) (thickness 0.15)) (justify mirror))
    )
    (fp_text value "R_12k_0402" (at -0.005 -1.25 90) (layer "B.Fab")
        (effects (font (size 1 1) (thickness 0.15)) (justify mirror))
    )
    (fp_text user "${REFERENCE}" (at 0 0 90) (layer "B.Fab")
        (effects (font (size 0.25 0.25) (thickness 0.04)) (justify mirror))
    )
    (fp_text user "Author: Antmicro" (at -0.95 -4.169 90) (layer "B.Fab") hide
        (effects (font (size 0.7 0.7) (thickness 0.15)) (justify left bottom mirror))
    )
    (fp_text user "License: Apache-2.0" (at -0.95 -5.169 90) (layer "B.Fab") hide
        (effects (font (size 0.7 0.7) (thickness 0.15)) (justify left bottom mirror))
    )
    (fp_rect (start -0.925 0.47) (end 0.925 -0.47)
      (stroke (width 0.05) (type default)) (fill none) (layer "B.CrtYd"))
    (fp_rect (start -0.5 0.25) (end 0.5 -0.25)
      (stroke (width 0.15) (type solid)) (fill none) (layer "B.Fab"))
    (pad "1" smd roundrect (at -0.48 0 270) (size 0.59 0.64) (layers "B.Cu" "B.Paste" "B.Mask") (roundrect_rratio 0.25)
      (net 433 "Net-(U14-REF)") (pintype "passive"))
    (pad "2" smd roundrect (at 0.48 0 270) (size 0.59 0.64) (layers "B.Cu" "B.Paste" "B.Mask") (roundrect_rratio 0.25)
      (net 1 "GND") (pintype "passive"))
  )
	(footprint "antmicro-footprints:R_0402_1005Metric" (layer "B.Cu")
    (at 133.1 86.325 90)
    (descr "Resistor SMD 0402")
    (tags "resistor SMD 0402")
    (property "Author" "Antmicro")
    (property "License" "Apache-2.0")
    (property "MPN" "CR0402-FX-1001GLF")
    (property "Manufacturer" "Bourns")
    (property "Public" "False")
    (property "Sheetfile" "interfaces.kicad_sch")
    (property "Sheetname" "Interfaces")
    (property "Tolerance" "1%")
    (property "Val" "1k")
    (property "ki_description" "SMD Chip Resistor, 1 kohm, ± 1%, 63 mW, 0402 [1005 Metric], Thick Film, General Purpose")
    (property "ki_keywords" "0402, SMT, RESISTOR, PASSIVE")
    (attr smd)
    (fp_text reference "R148" (at -2.39 0.01 90) (layer "B.SilkS")
        (effects (font (size 0.7 0.7) (thickness 0.15)) (justify mirror))
    )
    (fp_text value "R_1k_0402" (at 0 -1.17 90) (layer "B.Fab")
        (effects (font (size 1 1) (thickness 0.15)) (justify mirror))
    )
    (fp_text user "${REFERENCE}" (at 0 0 90) (layer "B.Fab")
        (effects (font (size 0.25 0.25) (thickness 0.04)) (justify mirror))
    )
    (fp_text user "License: Apache-2.0" (at -0.95 -5.169 270) (layer "B.Fab") hide
        (effects (font (size 0.7 0.7) (thickness 0.15)) (justify left bottom mirror))
    )
    (fp_text user "Author: Antmicro" (at -0.95 -4.169 270) (layer "B.Fab") hide
        (effects (font (size 0.7 0.7) (thickness 0.15)) (justify left bottom mirror))
    )
    (fp_rect (start -0.925 0.47) (end 0.925 -0.47)
      (stroke (width 0.05) (type default)) (fill none) (layer "B.CrtYd"))
    (fp_rect (start -0.5 0.25) (end 0.5 -0.25)
      (stroke (width 0.15) (type solid)) (fill none) (layer "B.Fab"))
    (pad "1" smd roundrect (at -0.48 0 90) (size 0.59 0.64) (layers "B.Cu" "B.Paste" "B.Mask") (roundrect_rratio 0.25)
      (net 2 "VCC3V3") (pintype "passive"))
    (pad "2" smd roundrect (at 0.48 0 90) (size 0.59 0.64) (layers "B.Cu" "B.Paste" "B.Mask") (roundrect_rratio 0.25)
      (net 432 "Net-(U14-~{RESET})") (pintype "passive"))
  )
	(footprint "antmicro-footprints:R_0402_1005Metric" (layer "B.Cu")
    (at 134.1 86.325 -90)
    (descr "Resistor SMD 0402")
    (tags "resistor SMD 0402")
    (property "Author" "Antmicro")
    (property "DNP" "DNP")
    (property "License" "Apache-2.0")
    (property "MPN" "CR0402-FX-1002GLF")
    (property "Manufacturer" "Bourns")
    (property "Public" "False")
    (property "Sheetfile" "interfaces.kicad_sch")
    (property "Sheetname" "Interfaces")
    (property "Tolerance" "1%")
    (property "Val" "10k")
    (property "dnp" "")
    (property "exclude_from_bom" "")
    (property "ki_description" "SMD Chip Resistor, 10 kohm, ± 1%, 62.5 mW, 0402 [1005 Metric], Thick Film, General Purpose")
    (property "ki_keywords" "0402, SMT, RESISTOR, PASSIVE")
    (attr smd exclude_from_pos_files exclude_from_bom)
    (fp_text reference "R147" (at 2.4 0.1 90) (layer "B.SilkS")
        (effects (font (size 0.7 0.7) (thickness 0.15)) (justify mirror))
    )
    (fp_text value "R_10k_0402" (at 0 -1.17 90) (layer "B.Fab")
        (effects (font (size 1 1) (thickness 0.15)) (justify mirror))
    )
    (fp_text user "${REFERENCE}" (at 0 0 90) (layer "B.Fab")
        (effects (font (size 0.25 0.25) (thickness 0.04)) (justify mirror))
    )
    (fp_text user "License: Apache-2.0" (at -0.95 -5.169 90) (layer "B.Fab") hide
        (effects (font (size 0.7 0.7) (thickness 0.15)) (justify left bottom mirror))
    )
    (fp_text user "Author: Antmicro" (at -0.95 -4.169 90) (layer "B.Fab") hide
        (effects (font (size 0.7 0.7) (thickness 0.15)) (justify left bottom mirror))
    )
    (fp_rect (start -0.925 0.47) (end 0.925 -0.47)
      (stroke (width 0.05) (type default)) (fill none) (layer "B.CrtYd"))
    (fp_rect (start -0.5 0.25) (end 0.5 -0.25)
      (stroke (width 0.15) (type solid)) (fill none) (layer "B.Fab"))
    (pad "1" smd roundrect (at -0.48 0 270) (size 0.59 0.64) (layers "B.Cu" "B.Paste" "B.Mask") (roundrect_rratio 0.25)
      (net 432 "Net-(U14-~{RESET})") (pintype "passive"))
    (pad "2" smd roundrect (at 0.48 0 270) (size 0.59 0.64) (layers "B.Cu" "B.Paste" "B.Mask") (roundrect_rratio 0.25)
      (net 1 "GND") (pintype "passive"))
  )
	(footprint "antmicro-footprints:FB_0402_1005Metric" (layer "B.Cu")
    (at 137.5 83.675 -90)
    (descr "Ferrite Bead SMD 0402")
    (tags "ferrite bead SMD 0402")
    (property "Author" "Antmicro")
    (property "Current" "")
    (property "License" "Apache-2.0")
    (property "MPN" "BLM15AG601SN1D")
    (property "Manufacturer" "Murata")
    (property "Public" "False")
    (property "Sheetfile" "interfaces.kicad_sch")
    (property "Sheetname" "Interfaces")
    (property "Val" "600Z/0.3A")
    (property "ki_description" "Ferrite Bead, 0402 [1005 Metric], 600 ohm, 300 mA, BLM15AG_SN, 0.6 ohm, ± 25%, General use")
    (property "ki_keywords" "0402, SMT, FERRITE BEAD, PASSIVE")
    (attr smd)
    (fp_text reference "FB10" (at -2.585 -0.06 90) (layer "B.SilkS")
        (effects (font (size 0.7 0.7) (thickness 0.15)) (justify mirror))
    )
    (fp_text value "FB_600Z_0.3A_Murata-BLM15AG_0402" (at 0 -1.17 90) (layer "B.Fab")
        (effects (font (size 1 1) (thickness 0.15)) (justify mirror))
    )
    (fp_text user "Author: Antmicro" (at -0.95 -4.169 90) (layer "B.Fab") hide
        (effects (font (size 0.7 0.7) (thickness 0.15)) (justify left bottom mirror))
    )
    (fp_text user "${REFERENCE}" (at 0 0 90) (layer "B.Fab")
        (effects (font (size 0.25 0.25) (thickness 0.04)) (justify mirror))
    )
    (fp_text user "License: Apache-2.0" (at -0.95 -5.169 90) (layer "B.Fab") hide
        (effects (font (size 0.7 0.7) (thickness 0.15)) (justify left bottom mirror))
    )
    (fp_rect (start -0.925 0.47) (end 0.925 -0.47)
      (stroke (width 0.05) (type default)) (fill none) (layer "B.CrtYd"))
    (fp_rect (start -0.5 0.25) (end 0.5 -0.25)
      (stroke (width 0.15) (type solid)) (fill none) (layer "B.Fab"))
    (pad "1" smd roundrect (at -0.48 0 270) (size 0.59 0.64) (layers "B.Cu" "B.Paste" "B.Mask") (roundrect_rratio 0.25)
      (net 2 "VCC3V3") (pintype "passive"))
    (pad "2" smd roundrect (at 0.48 0 270) (size 0.59 0.64) (layers "B.Cu" "B.Paste" "B.Mask") (roundrect_rratio 0.25)
      (net 307 "Net-(U14-V_{PHY})") (pintype "passive"))
  )
	(footprint "antmicro-footprints:R_0402_1005Metric" (layer "B.Cu")
    (at 134.85 83.675 -90)
    (descr "Resistor SMD 0402")
    (tags "resistor SMD 0402")
    (property "Author" "Antmicro")
    (property "DNP" "DNP")
    (property "License" "Apache-2.0")
    (property "MPN" "CR0402-FX-4701GLF")
    (property "Manufacturer" "Bourns")
    (property "Public" "False")
    (property "Sheetfile" "interfaces.kicad_sch")
    (property "Sheetname" "Interfaces")
    (property "Tolerance" "1%")
    (property "Val" "4k7")
    (property "dnp" "")
    (property "exclude_from_bom" "")
    (property "ki_description" "SMD Chip Resistor, 4.7 kohm, ± 1%, 62.5 mW, 0402 [1005 Metric], Thick Film, General Purpose")
    (property "ki_keywords" "0402, SMT, RESISTOR, PASSIVE")
    (attr smd exclude_from_pos_files exclude_from_bom)
    (fp_text reference "R146" (at -2.551667 -0.11 90) (layer "B.SilkS")
        (effects (font (size 0.7 0.7) (thickness 0.15)) (justify mirror))
    )
    (fp_text value "R_4k7_0402" (at 0 -1.17 90) (layer "B.Fab")
        (effects (font (size 1 1) (thickness 0.15)) (justify mirror))
    )
    (fp_text user "License: Apache-2.0" (at -0.95 -5.169 90) (layer "B.Fab") hide
        (effects (font (size 0.7 0.7) (thickness 0.15)) (justify left bottom mirror))
    )
    (fp_text user "${REFERENCE}" (at 0 0 90) (layer "B.Fab")
        (effects (font (size 0.25 0.25) (thickness 0.04)) (justify mirror))
    )
    (fp_text user "Author: Antmicro" (at -0.95 -4.169 90) (layer "B.Fab") hide
        (effects (font (size 0.7 0.7) (thickness 0.15)) (justify left bottom mirror))
    )
    (fp_rect (start -0.925 0.47) (end 0.925 -0.47)
      (stroke (width 0.05) (type default)) (fill none) (layer "B.CrtYd"))
    (fp_rect (start -0.5 0.25) (end 0.5 -0.25)
      (stroke (width 0.15) (type solid)) (fill none) (layer "B.Fab"))
    (pad "1" smd roundrect (at -0.48 0 270) (size 0.59 0.64) (layers "B.Cu" "B.Paste" "B.Mask") (roundrect_rratio 0.25)
      (net 415 "VBUS") (pintype "passive"))
    (pad "2" smd roundrect (at 0.48 0 270) (size 0.59 0.64) (layers "B.Cu" "B.Paste" "B.Mask") (roundrect_rratio 0.25)
      (net 432 "Net-(U14-~{RESET})") (pintype "passive"))
  )
	(footprint "antmicro-footprints:C_0603_1608Metric" (layer "B.Cu")
    (at 140.1 93.775)
    (descr "Capacitor SMD 0603")
    (tags "capacitor 0603")
    (property "Author" "Antmicro")
    (property "Dielectric" "")
    (property "License" "Apache-2.0")
    (property "MPN" "C0603C335M9PACTU")
    (property "Manufacturer" "KEMET")
    (property "Public" "False")
    (property "Sheetfile" "interfaces.kicad_sch")
    (property "Sheetname" "Interfaces")
    (property "Val" "3u3")
    (property "Voltage" "")
    (property "ki_description" "SMD Multilayer Ceramic Capacitor, 3.3 µF, 6.3 V, 0603 [1608 Metric], ± 20%, X5R, C Series KEMET")
    (property "ki_keywords" "0603, SMT, CAPACITOR, PASSIVE, CERAMIC, MLCC")
    (attr smd)
    (fp_text reference "C257" (at 3.11 0.07) (layer "B.SilkS")
        (effects (font (size 0.7 0.7) (thickness 0.15)) (justify mirror))
    )
    (fp_text value "C_3u3_0603" (at 0 -1.9) (layer "B.Fab")
        (effects (font (size 1 1) (thickness 0.15)) (justify mirror))
    )
    (fp_text user "Author: Antmicro" (at -1.682 -4.894 180) (layer "B.Fab") hide
        (effects (font (size 0.7 0.7) (thickness 0.15)) (justify left bottom mirror))
    )
    (fp_text user "${REFERENCE}" (at -1.682 -3.895 180) (layer "B.Fab") hide
        (effects (font (size 0.7 0.7) (thickness 0.15)) (justify left bottom mirror))
    )
    (fp_text user "License: Apache-2.0" (at -1.682 -5.895 180) (layer "B.Fab") hide
        (effects (font (size 0.7 0.7) (thickness 0.15)) (justify left bottom mirror))
    )
    (fp_line (start -0.15 -0.4) (end 0.15 -0.4)
      (stroke (width 0.15) (type solid)) (layer "B.SilkS"))
    (fp_line (start -0.15 0.4) (end 0.15 0.4)
      (stroke (width 0.15) (type solid)) (layer "B.SilkS"))
    (fp_rect (start -1.25 0.65) (end 1.25 -0.65)
      (stroke (width 0.05) (type solid)) (fill none) (layer "B.CrtYd"))
    (fp_rect (start -0.8 0.4) (end 0.8 -0.4)
      (stroke (width 0.15) (type solid)) (fill none) (layer "B.Fab"))
    (pad "1" smd roundrect (at -0.7 0) (size 0.8 1) (layers "B.Cu" "B.Paste" "B.Mask") (roundrect_rratio 0.2)
      (net 1 "GND") (pintype "passive"))
    (pad "2" smd roundrect (at 0.7 0) (size 0.8 1) (layers "B.Cu" "B.Paste" "B.Mask") (roundrect_rratio 0.2)
      (net 657 "VREGOUT") (pintype "passive"))
  )
)
